# T6G (Grand Teton) — schematic netlist excerpt (pin names and nets, part order shuffled) for the footprints in the layout excerpt that follows; sources: Cadence DE-HDL packaged netlist, KiCad conversion of 04192023_DAF0TMB3IC0_F0TG_MB_C_brd_V02_OCP.brd

C221  Q_CAP  4.7UF 6.3V 20% X6S  pkg 0402  page 323 : A = P0V9_CPU1_RT0_2A ; B = GND
PC282_2  Q_CAP  22UF 4V 20% X6S  pkg C0805  page 211 : A = PVDDCR_CPU0_P1 ; B = GND
C2466  Q_CAP  22UF 4V 20% X6S  pkg C0402  page 74 : A = PVDDCR_SOC_P1 ; B = GND

(kicad_pcb
	(version 20260206)
	(generator "pcbnew")
	(generator_version "10.0")
	(general
		(thickness 1.6)
		(legacy_teardrops no)
	)
	(paper "A4")
	(title_block
		(title "04192023_DAF0TMB3IC0_F0TG_MB_C_brd_V02_OCP.brd")
		(comment 1 "Grand Teton / footprints 8141-8143 of 8354")
	)
	(layers
		(0 "F.Cu" signal "TOP")
		(4 "In1.Cu" signal "GND")
		(6 "In2.Cu" signal "IN1")
		(8 "In3.Cu" signal "GND1")
		(10 "In4.Cu" signal "IN2")
		(12 "In5.Cu" signal "GND2")
		(14 "In6.Cu" signal "IN3")
		(16 "In7.Cu" signal "GND3")
		(18 "In8.Cu" signal "VCC")
		(20 "In9.Cu" signal "VCC1")
		(22 "In10.Cu" signal "GND4")
		(24 "In11.Cu" signal "IN4")
		(26 "In12.Cu" signal "GND5")
		(28 "In13.Cu" signal "IN5")
		(30 "In14.Cu" signal "GND6")
		(32 "In15.Cu" signal "IN6")
		(34 "In16.Cu" signal "GND7")
		(2 "B.Cu" signal "BOTTOM")
		(9 "F.Adhes" user "F.Adhesive")
		(11 "B.Adhes" user "B.Adhesive")
		(13 "F.Paste" user "Package Geometry/Pastemask Top")
		(15 "B.Paste" user "Package Geometry/Pastemask Bottom")
		(5 "F.SilkS" user "Ref Des/Silkscreen Top")
		(7 "B.SilkS" user "Ref Des/Silkscreen Bottom")
		(1 "F.Mask" user "Board Geometry/Soldermask Top")
		(3 "B.Mask" user "Board Geometry/Soldermask Bottom")
		(17 "Dwgs.User" user "User.Drawings")
		(19 "Cmts.User" user "User.Comments")
		(21 "Eco1.User" user "User.Eco1")
		(23 "Eco2.User" user "User.Eco2")
		(25 "Edge.Cuts" user "Board Geometry/Outline")
		(27 "Margin" user)
		(31 "F.CrtYd" user "Package Geometry/Place Bound Top")
		(29 "B.CrtYd" user "Package Geometry/Place Bound Bottom")
		(35 "F.Fab" user "Ref Des/Assembly Top")
		(33 "B.Fab" user "Ref Des/Assembly Bottom")
	)
	(footprint ""
		(layer "B.Cu")
		(at 109.895386 -253.432564)
		(property "Reference" "C2466"
			(at 0 0 0)
			(layer "B.SilkS")
			(hide yes)
			(effects
				(font
					(size 1.27 1.27)
				)
				(justify mirror)
			)
		)
		(property "Value" ""
			(at 0 0 0)
			(layer "B.Fab")
			(effects
				(font
					(size 1.27 1.27)
				)
				(justify mirror)
			)
		)
		(duplicate_pad_numbers_are_jumpers no)
		(fp_line
			(start -0.7874 -0.4064)
			(end -0.7874 0.4064)
			(stroke
				(width 0.1524)
				(type default)
			)
			(layer "B.SilkS")
		)
		(fp_line
			(start -0.7874 0.4064)
			(end 0.7874 0.4064)
			(stroke
				(width 0.1524)
				(type default)
			)
			(layer "B.SilkS")
		)
		(fp_line
			(start 0.7874 -0.4064)
			(end -0.7874 -0.4064)
			(stroke
				(width 0.1524)
				(type default)
			)
			(layer "B.SilkS")
		)
		(fp_line
			(start 0.7874 0.4064)
			(end 0.7874 -0.4064)
			(stroke
				(width 0.1524)
				(type default)
			)
			(layer "B.SilkS")
		)
		(fp_line
			(start -0.67945 -0.3048)
			(end -0.67945 0.3048)
			(stroke
				(width 0.1)
				(type default)
			)
			(layer "B.Fab")
		)
		(fp_line
			(start -0.67945 0.3048)
			(end -0.120396 0.3048)
			(stroke
				(width 0.1)
				(type default)
			)
			(layer "B.Fab")
		)
		(fp_line
			(start -0.12065 -0.3048)
			(end -0.67945 -0.3048)
			(stroke
				(width 0.1)
				(type default)
			)
			(layer "B.Fab")
		)
		(fp_line
			(start -0.12065 -0.2794)
			(end -0.12065 -0.3048)
			(stroke
				(width 0.1)
				(type default)
			)
			(layer "B.Fab")
		)
		(fp_line
			(start -0.120396 0.2794)
			(end 0.12065 0.2794)
			(stroke
				(width 0.1)
				(type default)
			)
			(layer "B.Fab")
		)
		(fp_line
			(start -0.120396 0.3048)
			(end -0.120396 0.2794)
			(stroke
				(width 0.1)
				(type default)
			)
			(layer "B.Fab")
		)
		(fp_line
			(start 0.12065 -0.305054)
			(end 0.12065 -0.2794)
			(stroke
				(width 0.1)
				(type default)
			)
			(layer "B.Fab")
		)
		(fp_line
			(start 0.12065 -0.2794)
			(end -0.12065 -0.2794)
			(stroke
				(width 0.1)
				(type default)
			)
			(layer "B.Fab")
		)
		(fp_line
			(start 0.12065 0.2794)
			(end 0.12065 0.3048)
			(stroke
				(width 0.1)
				(type default)
			)
			(layer "B.Fab")
		)
		(fp_line
			(start 0.12065 0.3048)
			(end 0.67945 0.3048)
			(stroke
				(width 0.1)
				(type default)
			)
			(layer "B.Fab")
		)
		(fp_line
			(start 0.67945 -0.305054)
			(end 0.12065 -0.305054)
			(stroke
				(width 0.1)
				(type default)
			)
			(layer "B.Fab")
		)
		(fp_line
			(start 0.67945 0.3048)
			(end 0.67945 -0.305054)
			(stroke
				(width 0.1)
				(type default)
			)
			(layer "B.Fab")
		)
		(pad "1" smd circle
			(at 0.40005 0 180)
			(size 0 0)
			(layers "B.Cu" "B.Mask" "B.Paste")
			(net "PVDDCR_SOC_P1")
		)
		(pad "2" smd circle
			(at -0.40005 0 180)
			(size 0 0)
			(layers "B.Cu" "B.Mask" "B.Paste")
			(net "GND")
		)
	)
	(footprint ""
		(layer "B.Cu")
		(at 94.373954 -191.358012 90)
		(property "Reference" "PC282_2"
			(at 0 0 90)
			(layer "B.SilkS")
			(hide yes)
			(effects
				(font
					(size 1.27 1.27)
				)
				(justify mirror)
			)
		)
		(property "Value" ""
			(at 0 0 90)
			(layer "B.Fab")
			(effects
				(font
					(size 1.27 1.27)
				)
				(justify mirror)
			)
		)
		(duplicate_pad_numbers_are_jumpers no)
		(fp_line
			(start 1.524 -0.762)
			(end -1.524 -0.762)
			(stroke
				(width 0.1524)
				(type default)
			)
			(layer "B.SilkS")
		)
		(fp_line
			(start -1.524 -0.762)
			(end -1.524 0.762)
			(stroke
				(width 0.1524)
				(type default)
			)
			(layer "B.SilkS")
		)
		(fp_line
			(start 1.524 0.762)
			(end 1.524 -0.762)
			(stroke
				(width 0.1524)
				(type default)
			)
			(layer "B.SilkS")
		)
		(fp_line
			(start -1.524 0.762)
			(end 1.524 0.762)
			(stroke
				(width 0.1524)
				(type default)
			)
			(layer "B.SilkS")
		)
		(fp_line
			(start 1.1049 -0.724916)
			(end 1.1049 0.724916)
			(stroke
				(width 0.1)
				(type default)
			)
			(layer "B.Fab")
		)
		(fp_line
			(start -1.1049 -0.724916)
			(end 1.1049 -0.724916)
			(stroke
				(width 0.1)
				(type default)
			)
			(layer "B.Fab")
		)
		(fp_line
			(start 1.1049 0.724916)
			(end -1.1049 0.724916)
			(stroke
				(width 0.1)
				(type default)
			)
			(layer "B.Fab")
		)
		(fp_line
			(start -1.1049 0.724916)
			(end -1.1049 -0.724916)
			(stroke
				(width 0.1)
				(type default)
			)
			(layer "B.Fab")
		)
		(pad "1" smd rect
			(at 0.889 0 90)
			(size 1.016 1.27)
			(layers "B.Cu" "B.Mask" "B.Paste")
			(net "PVDDCR_CPU0_P1")
		)
		(pad "2" smd rect
			(at -0.889 0 90)
			(size 1.016 1.27)
			(layers "B.Cu" "B.Mask" "B.Paste")
			(net "GND")
		)
	)
	(footprint ""
		(layer "B.Cu")
		(at 46.487334 -391.340848 -90)
		(property "Reference" "C221"
			(at 0 0 90)
			(layer "B.SilkS")
			(hide yes)
			(effects
				(font
					(size 1.27 1.27)
				)
				(justify mirror)
			)
		)
		(property "Value" ""
			(at 0 0 90)
			(layer "B.Fab")
			(effects
				(font
					(size 1.27 1.27)
				)
				(justify mirror)
			)
		)
		(duplicate_pad_numbers_are_jumpers no)
		(fp_line
			(start -0.7874 0.4064)
			(end 0.7874 0.4064)
			(stroke
				(width 0.1524)
				(type default)
			)
			(layer "B.SilkS")
		)
		(fp_line
			(start 0.7874 0.4064)
			(end 0.7874 -0.4064)
			(stroke
				(width 0.1524)
				(type default)
			)
			(layer "B.SilkS")
		)
		(fp_line
			(start -0.7874 -0.4064)
			(end -0.7874 0.4064)
			(stroke
				(width 0.1524)
				(type default)
			)
			(layer "B.SilkS")
		)
		(fp_line
			(start 0.7874 -0.4064)
			(end -0.7874 -0.4064)
			(stroke
				(width 0.1524)
				(type default)
			)
			(layer "B.SilkS")
		)
		(fp_line
			(start -0.67945 0.3048)
			(end -0.120396 0.3048)
			(stroke
				(width 0.1)
				(type default)
			)
			(layer "B.Fab")
		)
		(fp_line
			(start -0.120396 0.3048)
			(end -0.120396 0.2794)
			(stroke
				(width 0.1)
				(type default)
			)
			(layer "B.Fab")
		)
		(fp_line
			(start 0.12065 0.3048)
			(end 0.67945 0.3048)
			(stroke
				(width 0.1)
				(type default)
			)
			(layer "B.Fab")
		)
		(fp_line
			(start 0.67945 0.3048)
			(end 0.67945 -0.305054)
			(stroke
				(width 0.1)
				(type default)
			)
			(layer "B.Fab")
		)
		(fp_line
			(start -0.120396 0.2794)
			(end 0.12065 0.2794)
			(stroke
				(width 0.1)
				(type default)
			)
			(layer "B.Fab")
		)
		(fp_line
			(start 0.12065 0.2794)
			(end 0.12065 0.3048)
			(stroke
				(width 0.1)
				(type default)
			)
			(layer "B.Fab")
		)
		(fp_line
			(start -0.12065 -0.2794)
			(end -0.12065 -0.3048)
			(stroke
				(width 0.1)
				(type default)
			)
			(layer "B.Fab")
		)
		(fp_line
			(start 0.12065 -0.2794)
			(end -0.12065 -0.2794)
			(stroke
				(width 0.1)
				(type default)
			)
			(layer "B.Fab")
		)
		(fp_line
			(start -0.67945 -0.3048)
			(end -0.67945 0.3048)
			(stroke
				(width 0.1)
				(type default)
			)
			(layer "B.Fab")
		)
		(fp_line
			(start -0.12065 -0.3048)
			(end -0.67945 -0.3048)
			(stroke
				(width 0.1)
				(type default)
			)
			(layer "B.Fab")
		)
		(fp_line
			(start 0.12065 -0.305054)
			(end 0.12065 -0.2794)
			(stroke
				(width 0.1)
				(type default)
			)
			(layer "B.Fab")
		)
		(fp_line
			(start 0.67945 -0.305054)
			(end 0.12065 -0.305054)
			(stroke
				(width 0.1)
				(type default)
			)
			(layer "B.Fab")
		)
		(pad "1" smd circle
			(at 0.40005 0 90)
			(size 0 0)
			(layers "B.Cu" "B.Mask" "B.Paste")
			(net "P0V9_CPU1_RT0_2A")
		)
		(pad "2" smd circle
			(at -0.40005 0 90)
			(size 0 0)
			(layers "B.Cu" "B.Mask" "B.Paste")
			(net "GND")
		)
	)
)
